(kicad_pcb
	(version 20260206)
	(generator "pcbnew")
	(generator_version "10.0")
	(general
		(thickness 1.6)
		(legacy_teardrops no)
	)
	(paper "A4")
	(title_block
		(title "Wiwynn_Tioga_Pass_MB.brd")
		(comment 1 "Tioga Pass / footprints 2324-2327 of 4770")
	)
	(layers
		(0 "F.Cu" signal "TOP")
		(4 "In1.Cu" signal "L2GND")
		(6 "In2.Cu" signal "L3")
		(8 "In3.Cu" signal "L4GND")
		(10 "In4.Cu" signal "L5")
		(12 "In5.Cu" signal "L6GND")
		(14 "In6.Cu" signal "L7VCC")
		(16 "In7.Cu" signal "L8VCC")
		(18 "In8.Cu" signal "L9GND")
		(20 "In9.Cu" signal "L10")
		(22 "In10.Cu" signal "L11GND")
		(24 "In11.Cu" signal "L12")
		(26 "In12.Cu" signal "L13GND")
		(2 "B.Cu" signal "BOTTOM")
		(9 "F.Adhes" user "F.Adhesive")
		(11 "B.Adhes" user "B.Adhesive")
		(13 "F.Paste" user "Package Geometry/Pastemask Top")
		(15 "B.Paste" user "Package Geometry/Pastemask Bottom")
		(5 "F.SilkS" user "Ref Des/Silkscreen Top")
		(7 "B.SilkS" user "Ref Des/Silkscreen Bottom")
		(1 "F.Mask" user "Board Geometry/Soldermask Top")
		(3 "B.Mask" user "Board Geometry/Soldermask Bottom")
		(17 "Dwgs.User" user "User.Drawings")
		(19 "Cmts.User" user "User.Comments")
		(21 "Eco1.User" user "User.Eco1")
		(23 "Eco2.User" user "User.Eco2")
		(25 "Edge.Cuts" user "Board Geometry/Outline")
		(27 "Margin" user)
		(31 "F.CrtYd" user "Package Geometry/Place Bound Top")
		(29 "B.CrtYd" user "Package Geometry/Place Bound Bottom")
		(35 "F.Fab" user "Ref Des/Assembly Top")
		(33 "B.Fab" user "Ref Des/Assembly Bottom")
	)
	(footprint ""
		(layer "F.Cu")
		(at 177.165 -78.867 90)
		(property "Reference" "R4D22"
			(at 0 0 90)
			(layer "F.SilkS")
			(hide yes)
			(effects
				(font
					(size 1.27 1.27)
				)
			)
		)
		(property "Value" ""
			(at 0 0 90)
			(layer "F.Fab")
			(effects
				(font
					(size 1.27 1.27)
				)
			)
		)
		(duplicate_pad_numbers_are_jumpers no)
		(fp_poly
			(pts
				(xy -0.2794 -0.1016) (xy 0.2794 -0.1016) (xy 0.2794 0.9906) (xy -0.2794 0.9906)
			)
			(stroke
				(width 0)
				(type default)
			)
			(fill no)
			(layer "F.CrtYd")
		)
		(fp_line
			(start 0.2794 -0.1016)
			(end -0.2794 -0.1016)
			(stroke
				(width 0.1)
				(type default)
			)
			(layer "F.Fab")
		)
		(fp_line
			(start -0.2794 -0.1016)
			(end -0.2794 0.9906)
			(stroke
				(width 0.1)
				(type default)
			)
			(layer "F.Fab")
		)
		(fp_line
			(start 0.2794 0.9906)
			(end 0.2794 -0.1016)
			(stroke
				(width 0.1)
				(type default)
			)
			(layer "F.Fab")
		)
		(fp_line
			(start -0.2794 0.9906)
			(end 0.2794 0.9906)
			(stroke
				(width 0.1)
				(type default)
			)
			(layer "F.Fab")
		)
		(pad "1" smd rect
			(at 0 0 90)
			(size 0.508 0.508)
			(layers "F.Cu" "F.Mask" "F.Paste")
			(net "CLK_100M_CPU0_BCLK1_R_DP")
		)
		(pad "2" smd rect
			(at 0 0.889 90)
			(size 0.508 0.508)
			(layers "F.Cu" "F.Mask" "F.Paste")
			(net "CLK_100M_CPU0_BCLK1_DP")
		)
		(zone
			(layer "F.Cu")
			(hatch none 0.5)
			(connect_pads
				(clearance 0)
			)
			(min_thickness 0.25)
			(keepout
				(tracks allowed)
				(vias not_allowed)
				(pads allowed)
				(copperpour not_allowed)
				(footprints allowed)
			)
			(placement
				(enabled no)
				(sheetname "")
			)
			(fill
				(thermal_gap 0.5)
				(thermal_bridge_width 0.5)
				(island_removal_mode 0)
			)
			(polygon
				(pts
					(xy 177.419 -78.613) (xy 177.419 -79.121) (xy 177.8 -79.121) (xy 177.8 -78.613)
				)
			)
		)
		(zone
			(layer "F.Cu")
			(hatch none 0.5)
			(connect_pads
				(clearance 0)
			)
			(min_thickness 0.25)
			(keepout
				(tracks not_allowed)
				(vias allowed)
				(pads allowed)
				(copperpour not_allowed)
				(footprints allowed)
			)
			(placement
				(enabled no)
				(sheetname "")
			)
			(fill
				(thermal_gap 0.5)
				(thermal_bridge_width 0.5)
				(island_removal_mode 0)
			)
			(polygon
				(pts
					(xy 177.8 -78.613) (xy 177.8 -79.121) (xy 177.419 -79.121) (xy 177.419 -78.613)
				)
			)
		)
	)
	(footprint ""
		(layer "F.Cu")
		(at 87.158068 -3.3528 -90)
		(property "Reference" "C2G11"
			(at 1.848866 0.752348 270)
			(unlocked yes)
			(layer "F.SilkS")
			(effects
				(font
					(size 1.27 0.9652)
					(thickness 0.1524)
				)
			)
		)
		(property "Value" ""
			(at 0 0 270)
			(layer "F.Fab")
			(effects
				(font
					(size 1.27 1.27)
				)
			)
		)
		(duplicate_pad_numbers_are_jumpers no)
		(fp_rect
			(start -0.500126 1.598422)
			(end 0.500126 -0.201422)
			(stroke
				(width 0)
				(type default)
			)
			(fill no)
			(layer "F.CrtYd")
		)
		(fp_line
			(start -0.500126 1.598422)
			(end -0.500126 -0.201422)
			(stroke
				(width 0.1)
				(type default)
			)
			(layer "F.Fab")
		)
		(fp_line
			(start 0.500126 1.598422)
			(end -0.500126 1.598422)
			(stroke
				(width 0.1)
				(type default)
			)
			(layer "F.Fab")
		)
		(fp_line
			(start -0.500126 -0.201422)
			(end 0.500126 -0.201422)
			(stroke
				(width 0.1)
				(type default)
			)
			(layer "F.Fab")
		)
		(fp_line
			(start 0.500126 -0.201422)
			(end 0.500126 1.598422)
			(stroke
				(width 0.1)
				(type default)
			)
			(layer "F.Fab")
		)
		(pad "1" smd rect
			(at 0 0 180)
			(size 0.889 0.9906)
			(layers "F.Cu" "F.Mask" "F.Paste")
			(net "PVDDQ_GHJ")
		)
		(pad "2" smd rect
			(at 0 1.397 180)
			(size 0.889 0.9906)
			(layers "F.Cu" "F.Mask" "F.Paste")
			(net "GND")
		)
		(zone
			(layer "F.Cu")
			(hatch none 0.5)
			(connect_pads
				(clearance 0)
			)
			(min_thickness 0.25)
			(keepout
				(tracks allowed)
				(vias not_allowed)
				(pads allowed)
				(copperpour not_allowed)
				(footprints allowed)
			)
			(placement
				(enabled no)
				(sheetname "")
			)
			(fill
				(thermal_gap 0.5)
				(thermal_bridge_width 0.5)
				(island_removal_mode 0)
			)
			(polygon
				(pts
					(xy 86.205568 -3.8481) (xy 86.205568 -2.8575) (xy 86.713568 -2.8575) (xy 86.713568 -3.8481)
				)
			)
		)
		(zone
			(layer "F.Cu")
			(hatch none 0.5)
			(connect_pads
				(clearance 0)
			)
			(min_thickness 0.25)
			(keepout
				(tracks not_allowed)
				(vias allowed)
				(pads allowed)
				(copperpour not_allowed)
				(footprints allowed)
			)
			(placement
				(enabled no)
				(sheetname "")
			)
			(fill
				(thermal_gap 0.5)
				(thermal_bridge_width 0.5)
				(island_removal_mode 0)
			)
			(polygon
				(pts
					(xy 86.205568 -3.8481) (xy 86.205568 -2.8575) (xy 86.713568 -2.8575) (xy 86.713568 -3.8481)
				)
			)
		)
	)
	(footprint ""
		(layer "F.Cu")
		(at -1.999996 -54.909974 -90)
		(property "Reference" "J1E1"
			(at 0 0 270)
			(layer "F.SilkS")
			(hide yes)
			(effects
				(font
					(size 1.27 1.27)
				)
			)
		)
		(property "Value" "*"
			(at -18.3388 15.2273 270)
			(unlocked yes)
			(layer "F.Fab")
			(hide yes)
			(effects
				(font
					(size 1.27 1.016)
					(thickness 0.1524)
				)
			)
		)
		(property "Device Type" "FCI-CONN12-2R-GP_CONN-G5-FCI-CA"
			(at -18.3388 13.7033 270)
			(unlocked yes)
			(layer "F.Fab")
			(hide yes)
			(effects
				(font
					(size 1.27 1.016)
					(thickness 0.1524)
				)
			)
		)
		(duplicate_pad_numbers_are_jumpers no)
		(fp_line
			(start -6.1849 3.999992)
			(end 6.1849 3.999992)
			(stroke
				(width 0.1524)
				(type default)
			)
			(layer "F.SilkS")
		)
		(fp_line
			(start 6.1849 3.999992)
			(end 6.1849 -14.8971)
			(stroke
				(width 0.1524)
				(type default)
			)
			(layer "F.SilkS")
		)
		(fp_line
			(start -6.1849 -14.8971)
			(end -6.1849 3.999992)
			(stroke
				(width 0.1524)
				(type default)
			)
			(layer "F.SilkS")
		)
		(fp_line
			(start 6.1849 -14.8971)
			(end -6.1849 -14.8971)
			(stroke
				(width 0.1524)
				(type default)
			)
			(layer "F.SilkS")
		)
		(fp_poly
			(pts
				(xy -6.1849 3.999992) (xy 6.1849 3.999992) (xy 6.1849 -14.8971) (xy -6.1849 -14.8971)
			)
			(stroke
				(width 0)
				(type default)
			)
			(fill yes)
			(layer "F.SilkS")
		)
		(fp_poly
			(pts
				(arc
					(start -4.064 1.331976)
					(mid -4.318 1.585976)
					(end -4.572 1.331976)
				)
				(arc
					(start -4.572 0.569976)
					(mid -4.318 0.315976)
					(end -4.064 0.569976)
				)
			)
			(stroke
				(width 0)
				(type default)
			)
			(fill yes)
			(layer "F.SilkS")
		)
		(fp_poly
			(pts
				(arc
					(start -4.064 -0.66802)
					(mid -4.318 -0.41402)
					(end -4.572 -0.66802)
				)
				(arc
					(start -4.572 -1.43002)
					(mid -4.318 -1.68402)
					(end -4.064 -1.43002)
				)
			)
			(stroke
				(width 0)
				(type default)
			)
			(fill yes)
			(layer "F.SilkS")
		)
		(fp_poly
			(pts
				(arc
					(start -4.064 -2.668016)
					(mid -4.318 -2.414016)
					(end -4.572 -2.668016)
				)
				(arc
					(start -4.572 -3.430016)
					(mid -4.318 -3.684016)
					(end -4.064 -3.430016)
				)
			)
			(stroke
				(width 0)
				(type default)
			)
			(fill yes)
			(layer "F.SilkS")
		)
		(fp_poly
			(pts
				(arc
					(start -4.064 -6.668008)
					(mid -4.318 -6.414008)
					(end -4.572 -6.668008)
				)
				(arc
					(start -4.572 -7.430008)
					(mid -4.318 -7.684008)
					(end -4.064 -7.430008)
				)
			)
			(stroke
				(width 0)
				(type default)
			)
			(fill yes)
			(layer "F.SilkS")
		)
		(fp_poly
			(pts
				(arc
					(start -4.064 -8.668004)
					(mid -4.318 -8.414004)
					(end -4.572 -8.668004)
				)
				(arc
					(start -4.572 -9.430004)
					(mid -4.318 -9.684004)
					(end -4.064 -9.430004)
				)
			)
			(stroke
				(width 0)
				(type default)
			)
			(fill yes)
			(layer "F.SilkS")
		)
		(fp_poly
			(pts
				(arc
					(start -4.064 -10.668)
					(mid -4.318 -10.414)
					(end -4.572 -10.668)
				)
				(arc
					(start -4.572 -11.43)
					(mid -4.318 -11.684)
					(end -4.064 -11.43)
				)
			)
			(stroke
				(width 0)
				(type default)
			)
			(fill yes)
			(layer "F.SilkS")
		)
		(fp_rect
			(start -8.5598 6.5532)
			(end 8.5598 -16.5608)
			(stroke
				(width 0)
				(type default)
			)
			(fill no)
			(layer "B.CrtYd")
		)
		(fp_rect
			(start -5.9309 16.3449)
			(end 5.9309 -14.6431)
			(stroke
				(width 0)
				(type default)
			)
			(fill no)
			(layer "F.CrtYd")
		)
		(fp_poly
			(pts
				(xy -10.9347 21.3487) (xy -10.9347 -19.6469) (xy 10.9347 -19.6469) (xy 10.9347 -0.00635) (xy 6.4389 -0.00635)
				(xy 6.4389 -15.1511) (xy -6.4389 -15.1511) (xy -6.4389 16.8529) (xy 6.4389 16.8529) (xy 6.4389 0.00635)
				(xy 10.9347 0.00635) (xy 10.9347 21.3487)
			)
			(stroke
				(width 0)
				(type default)
			)
			(fill no)
			(layer "F.CrtYd")
		)
		(fp_poly
			(pts
				(xy -6.4389 16.8529) (xy -6.4389 -15.1511) (xy 6.4389 -15.1511) (xy 6.4389 -0.00635) (xy 5.9309 -0.00635)
				(xy 5.9309 -14.6431) (xy -5.9309 -14.6431) (xy -5.9309 16.3449) (xy 5.9309 16.3449) (xy 5.9309 0.00635)
				(xy 6.4389 0.00635) (xy 6.4389 16.8529)
			)
			(stroke
				(width 0)
				(type default)
			)
			(fill no)
			(layer "F.CrtYd")
		)
		(fp_rect
			(start -13.5636 11.557)
			(end 13.5636 -21.5646)
			(stroke
				(width 0)
				(type default)
			)
			(fill no)
			(layer "B.Fab")
		)
		(fp_rect
			(start -8.5598 6.5532)
			(end 8.5598 -16.5608)
			(stroke
				(width 0)
				(type default)
			)
			(fill no)
			(layer "B.Fab")
		)
		(fp_rect
			(start -15.9385 26.3525)
			(end 15.9385 -24.6507)
			(stroke
				(width 0)
				(type default)
			)
			(fill no)
			(layer "F.Fab")
		)
		(fp_rect
			(start -10.9347 21.3487)
			(end 10.9347 -19.6469)
			(stroke
				(width 0)
				(type default)
			)
			(fill no)
			(layer "F.Fab")
		)
		(fp_rect
			(start -6.4389 16.8529)
			(end 6.4389 -15.1511)
			(stroke
				(width 0)
				(type default)
			)
			(fill no)
			(layer "F.Fab")
		)
		(fp_text user "Slit"
			(at -2.31521 6.78307 270)
			(unlocked yes)
			(layer "F.SilkS")
			(effects
				(font
					(size 1.27 1.016)
					(thickness 0.1524)
				)
				(justify left)
			)
		)
		(fp_text user "Press Fit"
			(at -5.1054 -12.6111 270)
			(unlocked yes)
			(layer "F.SilkS")
			(effects
				(font
					(size 1.27 1.016)
					(thickness 0.1524)
				)
				(justify left)
			)
		)
		(fp_text user "Can not place BGA,CSP,Wave Solder Component"
			(at -25.73655 8.95604 270)
			(unlocked yes)
			(layer "B.Fab")
			(effects
				(font
					(size 1.27 1.016)
					(thickness 0.1524)
				)
				(justify left)
			)
		)
		(fp_text user "Can not place BGA,CSP,Wave Solder Component"
			(at -25.82926 18.53946 270)
			(unlocked yes)
			(layer "F.Fab")
			(effects
				(font
					(size 1.27 1.016)
					(thickness 0.1524)
				)
				(justify left)
			)
		)
		(fp_text user "High Limit 2mm"
			(at -8.4963 13.35786 270)
			(unlocked yes)
			(layer "F.Fab")
			(effects
				(font
					(size 1.27 1.016)
					(thickness 0.1524)
				)
				(justify left)
			)
		)
		(pad "" np_thru_hole circle
			(at 0 0 270)
			(size 0.254 0.254)
			(drill 2.1336)
			(layers "*.Cu" "*.Mask")
			(clearance 1.2954)
			(thermal_gap 1.2954)
		)
		(pad "1_1" thru_hole circle
			(at 2.999994 -6.999986 270)
			(size 1.1176 1.1176)
			(drill 0.749808)
			(layers "*.Cu" "*.Mask")
			(remove_unused_layers no)
			(net "P12V_PSU")
			(clearance 0.1778)
			(thermal_gap 0.1778)
		)
		(pad "1_2" thru_hole circle
			(at 2.999994 -8.999982 270)
			(size 1.1176 1.1176)
			(drill 0.749808)
			(layers "*.Cu" "*.Mask")
			(remove_unused_layers no)
			(net "P12V_PSU")
			(clearance 0.1778)
			(thermal_gap 0.1778)
		)
		(pad "1_3" thru_hole circle
			(at 2.999994 -10.999978 270)
			(size 1.1176 1.1176)
			(drill 0.749808)
			(layers "*.Cu" "*.Mask")
			(remove_unused_layers no)
			(net "P12V_PSU")
			(clearance 0.1778)
			(thermal_gap 0.1778)
		)
		(pad "2_1" thru_hole circle
			(at -2.999994 -6.999986 270)
			(size 1.1176 1.1176)
			(drill 0.749808)
			(layers "*.Cu" "*.Mask")
			(remove_unused_layers no)
			(net "P12V_PSU")
			(clearance 0.1778)
			(thermal_gap 0.1778)
		)
		(pad "2_2" thru_hole circle
			(at -2.999994 -8.999982 270)
			(size 1.1176 1.1176)
			(drill 0.749808)
			(layers "*.Cu" "*.Mask")
			(remove_unused_layers no)
			(net "P12V_PSU")
			(clearance 0.1778)
			(thermal_gap 0.1778)
		)
		(pad "2_3" thru_hole circle
			(at -2.999994 -10.999978 270)
			(size 1.1176 1.1176)
			(drill 0.749808)
			(layers "*.Cu" "*.Mask")
			(remove_unused_layers no)
			(net "P12V_PSU")
			(clearance 0.1778)
			(thermal_gap 0.1778)
		)
		(pad "3_1" thru_hole circle
			(at -2.999994 0.999998 270)
			(size 1.1176 1.1176)
			(drill 0.749808)
			(layers "*.Cu" "*.Mask")
			(remove_unused_layers no)
			(net "GND")
			(clearance 0.1778)
			(thermal_gap 0.1778)
		)
		(pad "3_2" thru_hole circle
			(at -2.999994 -0.999998 270)
			(size 1.1176 1.1176)
			(drill 0.749808)
			(layers "*.Cu" "*.Mask")
			(remove_unused_layers no)
			(net "GND")
			(clearance 0.1778)
			(thermal_gap 0.1778)
		)
		(pad "3_3" thru_hole circle
			(at -2.999994 -2.999994 270)
			(size 1.1176 1.1176)
			(drill 0.749808)
			(layers "*.Cu" "*.Mask")
			(remove_unused_layers no)
			(net "GND")
			(clearance 0.1778)
			(thermal_gap 0.1778)
		)
		(pad "4_1" thru_hole circle
			(at 2.999994 0.999998 270)
			(size 1.1176 1.1176)
			(drill 0.749808)
			(layers "*.Cu" "*.Mask")
			(remove_unused_layers no)
			(net "GND")
			(clearance 0.1778)
			(thermal_gap 0.1778)
		)
		(pad "4_2" thru_hole circle
			(at 2.999994 -0.999998 270)
			(size 1.1176 1.1176)
			(drill 0.749808)
			(layers "*.Cu" "*.Mask")
			(remove_unused_layers no)
			(net "GND")
			(clearance 0.1778)
			(thermal_gap 0.1778)
		)
		(pad "4_3" thru_hole circle
			(at 2.999994 -2.999994 270)
			(size 1.1176 1.1176)
			(drill 0.749808)
			(layers "*.Cu" "*.Mask")
			(remove_unused_layers no)
			(net "GND")
			(clearance 0.1778)
			(thermal_gap 0.1778)
		)
		(zone
			(layers "F.Cu" "B.Cu" "In1.Cu" "In2.Cu" "In3.Cu" "In4.Cu" "In5.Cu" "In6.Cu"
				"In7.Cu" "In8.Cu" "In9.Cu" "In10.Cu" "In11.Cu" "In12.Cu"
			)
			(hatch none 0.5)
			(connect_pads
				(clearance 0)
			)
			(min_thickness 0.25)
			(keepout
				(tracks not_allowed)
				(vias allowed)
				(pads allowed)
				(copperpour not_allowed)
				(footprints allowed)
			)
			(placement
				(enabled no)
				(sheetname "")
			)
			(fill
				(thermal_gap 0.5)
				(thermal_bridge_width 0.5)
				(island_removal_mode 0)
			)
			(polygon
				(pts
					(arc
						(start -0.628396 -54.909974)
						(mid -3.371596 -54.909974)
						(end -0.628396 -54.909974)
					)
				)
			)
		)
	)
	(footprint ""
		(layer "F.Cu")
		(at 336.677 -22.352 180)
		(property "Reference" "C7F13"
			(at 0 0 180)
			(layer "F.SilkS")
			(hide yes)
			(effects
				(font
					(size 1.27 1.27)
				)
			)
		)
		(property "Value" ""
			(at 0 0 180)
			(layer "F.Fab")
			(effects
				(font
					(size 1.27 1.27)
				)
			)
		)
		(duplicate_pad_numbers_are_jumpers no)
		(fp_poly
			(pts
				(xy 0.3048 -0.1016) (xy 0.3048 0.9906) (xy -0.3048 0.9906) (xy -0.3048 -0.1016)
			)
			(stroke
				(width 0)
				(type default)
			)
			(fill no)
			(layer "F.CrtYd")
		)
		(fp_line
			(start 0.3048 0.9906)
			(end 0.3048 -0.1016)
			(stroke
				(width 0.1)
				(type default)
			)
			(layer "F.Fab")
		)
		(fp_line
			(start 0.3048 -0.1016)
			(end -0.3048 -0.1016)
			(stroke
				(width 0.1)
				(type default)
			)
			(layer "F.Fab")
		)
		(fp_line
			(start -0.3048 0.9906)
			(end 0.3048 0.9906)
			(stroke
				(width 0.1)
				(type default)
			)
			(layer "F.Fab")
		)
		(fp_line
			(start -0.3048 -0.1016)
			(end -0.3048 0.9906)
			(stroke
				(width 0.1)
				(type default)
			)
			(layer "F.Fab")
		)
		(pad "1" smd rect
			(at 0 0 180)
			(size 0.508 0.508)
			(layers "F.Cu" "F.Mask" "F.Paste")
			(net "VR_COMP_PVPP_ABC")
		)
		(pad "2" smd rect
			(at 0 0.889 180)
			(size 0.508 0.508)
			(layers "F.Cu" "F.Mask" "F.Paste")
			(net "VR_FB_PVPP_ABC")
		)
		(zone
			(layer "F.Cu")
			(hatch none 0.5)
			(connect_pads
				(clearance 0)
			)
			(min_thickness 0.25)
			(keepout
				(tracks not_allowed)
				(vias allowed)
				(pads allowed)
				(copperpour not_allowed)
				(footprints allowed)
			)
			(placement
				(enabled no)
				(sheetname "")
			)
			(fill
				(thermal_gap 0.5)
				(thermal_bridge_width 0.5)
				(island_removal_mode 0)
			)
			(polygon
				(pts
					(xy 336.931 -22.987) (xy 336.423 -22.987) (xy 336.423 -22.606) (xy 336.931 -22.606)
				)
			)
		)
		(zone
			(layer "F.Cu")
			(hatch none 0.5)
			(connect_pads
				(clearance 0)
			)
			(min_thickness 0.25)
			(keepout
				(tracks allowed)
				(vias not_allowed)
				(pads allowed)
				(copperpour not_allowed)
				(footprints allowed)
			)
			(placement
				(enabled no)
				(sheetname "")
			)
			(fill
				(thermal_gap 0.5)
				(thermal_bridge_width 0.5)
				(island_removal_mode 0)
			)
			(polygon
				(pts
					(xy 336.931 -22.606) (xy 336.423 -22.606) (xy 336.423 -22.987) (xy 336.931 -22.987)
				)
			)
		)
	)
)
